(kicad_pcb
	(version 20260206)
	(generator "pcbnew")
	(generator_version "10.0")
	(general
		(thickness 1.6)
		(legacy_teardrops no)
	)
	(paper "A4")
	(title_block
		(title "01162023_DA0F0TEBIF0_F0T_Expander_BD_F_brd_V02_OCP.brd")
		(comment 1 "Grand Teton / footprints 1775-1781 of 9728")
	)
	(layers
		(0 "F.Cu" signal "TOP")
		(4 "In1.Cu" signal "GND")
		(6 "In2.Cu" signal "VCC")
		(8 "In3.Cu" signal "VCC1")
		(10 "In4.Cu" signal "GND1")
		(12 "In5.Cu" signal "IN1")
		(14 "In6.Cu" signal "GND2")
		(16 "In7.Cu" signal "IN2")
		(18 "In8.Cu" signal "GND3")
		(20 "In9.Cu" signal "IN3")
		(22 "In10.Cu" signal "GND4")
		(24 "In11.Cu" signal "IN4")
		(26 "In12.Cu" signal "GND5")
		(28 "In13.Cu" signal "IN5")
		(30 "In14.Cu" signal "GND6")
		(32 "In15.Cu" signal "IN6")
		(34 "In16.Cu" signal "GND7")
		(2 "B.Cu" signal "BOTTOM")
		(9 "F.Adhes" user "F.Adhesive")
		(11 "B.Adhes" user "B.Adhesive")
		(13 "F.Paste" user "Package Geometry/Pastemask Top")
		(15 "B.Paste" user "Package Geometry/Pastemask Bottom")
		(5 "F.SilkS" user "Ref Des/Silkscreen Top")
		(7 "B.SilkS" user "Ref Des/Silkscreen Bottom")
		(1 "F.Mask" user "Board Geometry/Soldermask Top")
		(3 "B.Mask" user "Board Geometry/Soldermask Bottom")
		(17 "Dwgs.User" user "User.Drawings")
		(19 "Cmts.User" user "User.Comments")
		(21 "Eco1.User" user "User.Eco1")
		(23 "Eco2.User" user "User.Eco2")
		(25 "Edge.Cuts" user "Board Geometry/Outline")
		(27 "Margin" user)
		(31 "F.CrtYd" user "Package Geometry/Place Bound Top")
		(29 "B.CrtYd" user "Package Geometry/Place Bound Bottom")
		(35 "F.Fab" user "Ref Des/Assembly Top")
		(33 "B.Fab" user "Ref Des/Assembly Bottom")
	)
	(footprint ""
		(layer "F.Cu")
		(at 327.533 -209.169)
		(property "Reference" "R5910"
			(at 0 0 0)
			(layer "F.SilkS")
			(hide yes)
			(effects
				(font
					(size 1.27 1.27)
				)
			)
		)
		(property "Value" ""
			(at 0 0 0)
			(layer "F.Fab")
			(effects
				(font
					(size 1.27 1.27)
				)
			)
		)
		(duplicate_pad_numbers_are_jumpers no)
		(fp_line
			(start -0.7874 -0.4064)
			(end 0.7874 -0.4064)
			(stroke
				(width 0.1524)
				(type default)
			)
			(layer "F.SilkS")
		)
		(fp_line
			(start -0.7874 0.4064)
			(end -0.7874 -0.4064)
			(stroke
				(width 0.1524)
				(type default)
			)
			(layer "F.SilkS")
		)
		(fp_line
			(start 0.7874 -0.4064)
			(end 0.7874 0.4064)
			(stroke
				(width 0.1524)
				(type default)
			)
			(layer "F.SilkS")
		)
		(fp_line
			(start 0.7874 0.4064)
			(end -0.7874 0.4064)
			(stroke
				(width 0.1524)
				(type default)
			)
			(layer "F.SilkS")
		)
		(fp_line
			(start -0.67945 -0.305054)
			(end -0.12065 -0.305054)
			(stroke
				(width 0.1)
				(type default)
			)
			(layer "F.Fab")
		)
		(fp_line
			(start -0.67945 0.3048)
			(end -0.67945 -0.305054)
			(stroke
				(width 0.1)
				(type default)
			)
			(layer "F.Fab")
		)
		(fp_line
			(start -0.12065 -0.305054)
			(end -0.12065 -0.2794)
			(stroke
				(width 0.1)
				(type default)
			)
			(layer "F.Fab")
		)
		(fp_line
			(start -0.12065 -0.2794)
			(end 0.12065 -0.2794)
			(stroke
				(width 0.1)
				(type default)
			)
			(layer "F.Fab")
		)
		(fp_line
			(start -0.12065 0.2794)
			(end -0.12065 0.3048)
			(stroke
				(width 0.1)
				(type default)
			)
			(layer "F.Fab")
		)
		(fp_line
			(start -0.12065 0.3048)
			(end -0.67945 0.3048)
			(stroke
				(width 0.1)
				(type default)
			)
			(layer "F.Fab")
		)
		(fp_line
			(start 0.120396 0.2794)
			(end -0.12065 0.2794)
			(stroke
				(width 0.1)
				(type default)
			)
			(layer "F.Fab")
		)
		(fp_line
			(start 0.120396 0.3048)
			(end 0.120396 0.2794)
			(stroke
				(width 0.1)
				(type default)
			)
			(layer "F.Fab")
		)
		(fp_line
			(start 0.12065 -0.3048)
			(end 0.67945 -0.3048)
			(stroke
				(width 0.1)
				(type default)
			)
			(layer "F.Fab")
		)
		(fp_line
			(start 0.12065 -0.2794)
			(end 0.12065 -0.3048)
			(stroke
				(width 0.1)
				(type default)
			)
			(layer "F.Fab")
		)
		(fp_line
			(start 0.67945 -0.3048)
			(end 0.67945 0.3048)
			(stroke
				(width 0.1)
				(type default)
			)
			(layer "F.Fab")
		)
		(fp_line
			(start 0.67945 0.3048)
			(end 0.120396 0.3048)
			(stroke
				(width 0.1)
				(type default)
			)
			(layer "F.Fab")
		)
		(pad "1" smd circle
			(at -0.40005 0)
			(size 0 0)
			(layers "F.Cu" "F.Mask" "F.Paste")
			(net "HSC_TIMER_N")
		)
		(pad "2" smd circle
			(at 0.40005 0)
			(size 0 0)
			(layers "F.Cu" "F.Mask" "F.Paste")
			(net "HSC_TIMER_R_N")
		)
	)
	(footprint ""
		(layer "F.Cu")
		(at 187.946792 -350.098614 90)
		(property "Reference" "C2537"
			(at 0 0 90)
			(layer "F.SilkS")
			(hide yes)
			(effects
				(font
					(size 1.27 1.27)
				)
			)
		)
		(property "Value" ""
			(at 0 0 90)
			(layer "F.Fab")
			(effects
				(font
					(size 1.27 1.27)
				)
			)
		)
		(duplicate_pad_numbers_are_jumpers no)
		(fp_line
			(start 0.299974 -0.150114)
			(end 0.299974 0.150114)
			(stroke
				(width 0.1)
				(type default)
			)
			(layer "F.Fab")
		)
		(fp_line
			(start -0.299974 -0.150114)
			(end 0.299974 -0.150114)
			(stroke
				(width 0.1)
				(type default)
			)
			(layer "F.Fab")
		)
		(fp_line
			(start 0.299974 0.150114)
			(end -0.299974 0.150114)
			(stroke
				(width 0.1)
				(type default)
			)
			(layer "F.Fab")
		)
		(fp_line
			(start -0.299974 0.150114)
			(end -0.299974 -0.150114)
			(stroke
				(width 0.1)
				(type default)
			)
			(layer "F.Fab")
		)
		(pad "1" smd rect
			(at -0.2667 0 90)
			(size 0.3048 0.381)
			(layers "F.Cu" "F.Mask" "F.Paste")
			(net "P5E_PEX1_STN4_TX_DN<67>")
		)
		(pad "2" smd rect
			(at 0.2667 0 90)
			(size 0.3048 0.381)
			(layers "F.Cu" "F.Mask" "F.Paste")
			(net "P5E_PEX1_STN4_TX_C_DN<67>")
		)
	)
	(footprint ""
		(layer "F.Cu")
		(at 450.573902 -26.31186 -90)
		(property "Reference" "U407"
			(at -0.05334 -2.461768 90)
			(unlocked yes)
			(layer "F.SilkS")
			(effects
				(font
					(size 0.7874 0.5842)
					(thickness 0.1524)
				)
			)
		)
		(property "Value" ""
			(at 0 0 270)
			(layer "F.Fab")
			(effects
				(font
					(size 1.27 1.27)
				)
			)
		)
		(duplicate_pad_numbers_are_jumpers no)
		(fp_line
			(start -1.949958 1.610106)
			(end -1.949958 -1.610106)
			(stroke
				(width 0.1524)
				(type default)
			)
			(layer "F.SilkS")
		)
		(fp_line
			(start 1.949958 1.610106)
			(end -1.949958 1.610106)
			(stroke
				(width 0.1524)
				(type default)
			)
			(layer "F.SilkS")
		)
		(fp_line
			(start 1.949958 -1.560068)
			(end 1.949958 1.610106)
			(stroke
				(width 0.1524)
				(type default)
			)
			(layer "F.SilkS")
		)
		(fp_line
			(start -1.949958 -1.610106)
			(end 1.949958 -1.610106)
			(stroke
				(width 0.1524)
				(type default)
			)
			(layer "F.SilkS")
		)
		(fp_line
			(start -0.750062 1.560068)
			(end -0.750062 -1.560068)
			(stroke
				(width 0.1)
				(type default)
			)
			(layer "F.Fab")
		)
		(fp_line
			(start 0.750062 1.560068)
			(end -0.750062 1.560068)
			(stroke
				(width 0.1)
				(type default)
			)
			(layer "F.Fab")
		)
		(fp_line
			(start -0.750062 -1.560068)
			(end 0.750062 -1.560068)
			(stroke
				(width 0.1)
				(type default)
			)
			(layer "F.Fab")
		)
		(fp_line
			(start 0.750062 -1.560068)
			(end 0.750062 1.560068)
			(stroke
				(width 0.1)
				(type default)
			)
			(layer "F.Fab")
		)
		(pad "D" smd rect
			(at 1.100074 0 180)
			(size 1.016 1.4224)
			(layers "F.Cu" "F.Mask" "F.Paste")
			(net "SSD15_LED_ISO_N")
		)
		(pad "G" smd rect
			(at -1.100074 -0.94996 180)
			(size 1.016 1.4224)
			(layers "F.Cu" "F.Mask" "F.Paste")
			(net "SSD15_LED_R")
		)
		(pad "S" smd rect
			(at -1.100074 0.94996 180)
			(size 1.016 1.4224)
			(layers "F.Cu" "F.Mask" "F.Paste")
			(net "GND")
		)
	)
	(footprint ""
		(layer "F.Cu")
		(at 147.219162 -240.716562 180)
		(property "Reference" "U431"
			(at -4.548632 0.282702 0)
			(unlocked yes)
			(layer "F.SilkS")
			(effects
				(font
					(size 0.7874 0.5842)
					(thickness 0.1524)
				)
				(justify left)
			)
		)
		(property "Value" ""
			(at 0 0 180)
			(layer "F.Fab")
			(effects
				(font
					(size 1.27 1.27)
				)
			)
		)
		(duplicate_pad_numbers_are_jumpers no)
		(fp_line
			(start 1.525016 1.525016)
			(end 1.525016 1.3208)
			(stroke
				(width 0.1524)
				(type default)
			)
			(layer "F.SilkS")
		)
		(fp_line
			(start 1.525016 1.525016)
			(end -1.525016 1.525016)
			(stroke
				(width 0.1524)
				(type default)
			)
			(layer "F.SilkS")
		)
		(fp_line
			(start 1.525016 -1.3208)
			(end 1.525016 -1.525016)
			(stroke
				(width 0.1524)
				(type default)
			)
			(layer "F.SilkS")
		)
		(fp_line
			(start 1.525016 -1.525016)
			(end 0.9398 -1.525016)
			(stroke
				(width 0.1524)
				(type default)
			)
			(layer "F.SilkS")
		)
		(fp_line
			(start 1.525016 -1.525016)
			(end -1.525016 -1.525016)
			(stroke
				(width 0.1524)
				(type default)
			)
			(layer "F.SilkS")
		)
		(fp_line
			(start 0.9906 1.525016)
			(end 1.525016 1.525016)
			(stroke
				(width 0.1524)
				(type default)
			)
			(layer "F.SilkS")
		)
		(fp_line
			(start -0.8636 -1.525016)
			(end -1.525016 -1.525016)
			(stroke
				(width 0.1524)
				(type default)
			)
			(layer "F.SilkS")
		)
		(fp_line
			(start -1.525016 1.525016)
			(end -0.889 1.525016)
			(stroke
				(width 0.1524)
				(type default)
			)
			(layer "F.SilkS")
		)
		(fp_line
			(start -1.525016 1.3208)
			(end -1.525016 1.525016)
			(stroke
				(width 0.1524)
				(type default)
			)
			(layer "F.SilkS")
		)
		(fp_line
			(start -1.525016 -1.525016)
			(end -1.525016 -1.3208)
			(stroke
				(width 0.1524)
				(type default)
			)
			(layer "F.SilkS")
		)
		(fp_poly
			(pts
				(xy -2.253996 -0.994156) (xy -1.954022 -1.894332) (xy -2.55397 -1.894332)
			)
			(stroke
				(width 0)
				(type default)
			)
			(fill yes)
			(layer "F.SilkS")
		)
		(fp_line
			(start 1.525016 1.525016)
			(end -1.525016 1.525016)
			(stroke
				(width 0.1)
				(type default)
			)
			(layer "F.Fab")
		)
		(fp_line
			(start 1.525016 -1.525016)
			(end 1.525016 1.525016)
			(stroke
				(width 0.1)
				(type default)
			)
			(layer "F.Fab")
		)
		(fp_line
			(start -1.525016 1.525016)
			(end -1.525016 -1.525016)
			(stroke
				(width 0.1)
				(type default)
			)
			(layer "F.Fab")
		)
		(fp_line
			(start -1.525016 -1.525016)
			(end 1.525016 -1.525016)
			(stroke
				(width 0.1)
				(type default)
			)
			(layer "F.Fab")
		)
		(fp_poly
			(pts
				(xy -2.0701 -0.999998) (xy -2.977896 -1.302512) (xy -2.977896 -0.697484)
			)
			(stroke
				(width 0)
				(type default)
			)
			(fill yes)
			(layer "F.Fab")
		)
		(pad "1" smd rect
			(at -1.550162 -0.999998 90)
			(size 0.2794 0.9144)
			(layers "F.Cu" "F.Mask" "F.Paste")
			(net "P1V8_PLL0_PEX1")
		)
		(pad "2" smd rect
			(at -1.550162 -0.500126 90)
			(size 0.2794 0.9144)
			(layers "F.Cu" "F.Mask" "F.Paste")
			(net "P1V8_PLL0_PEX1")
		)
		(pad "3" smd rect
			(at -1.550162 0 90)
			(size 0.2794 0.9144)
			(layers "F.Cu" "F.Mask" "F.Paste")
			(net "P1V8_PLL0_PEX1")
		)
		(pad "4" smd rect
			(at -1.550162 0.500126 90)
			(size 0.2794 0.9144)
			(layers "F.Cu" "F.Mask" "F.Paste")
			(net "P1V8_PLL_PEX1_ADJ")
		)
		(pad "5" smd rect
			(at -1.550162 0.999998 270)
			(size 0.2794 0.9144)
			(layers "F.Cu" "F.Mask" "F.Paste")
			(net "PWRGD_PEX1_P1V8_PLL")
		)
		(pad "6" smd rect
			(at 1.550162 0.999998 270)
			(size 0.2794 0.9144)
			(layers "F.Cu" "F.Mask" "F.Paste")
			(net "PEX1_P1V8_PLL_EN")
		)
		(pad "7" smd rect
			(at 1.550162 0.500126 90)
			(size 0.2794 0.9144)
			(layers "F.Cu" "F.Mask" "F.Paste")
			(net "P3V3_AUX")
		)
		(pad "8" smd rect
			(at 1.550162 0 90)
			(size 0.2794 0.9144)
			(layers "F.Cu" "F.Mask" "F.Paste")
			(net "P3V3_AUX")
		)
		(pad "9" smd rect
			(at 1.550162 -0.500126 90)
			(size 0.2794 0.9144)
			(layers "F.Cu" "F.Mask" "F.Paste")
			(net "P3V3_AUX")
		)
		(pad "10" smd rect
			(at 1.550162 -0.999998 90)
			(size 0.2794 0.9144)
			(layers "F.Cu" "F.Mask" "F.Paste")
			(net "P5V_AUX")
		)
		(pad "TH" smd rect
			(at 0 0 180)
			(size 1.7526 2.667)
			(layers "F.Cu" "F.Mask" "F.Paste")
			(net "GND")
		)
		(zone
			(layer "F.Cu")
			(hatch none 0.5)
			(connect_pads
				(clearance 0)
			)
			(min_thickness 0.25)
			(keepout
				(tracks not_allowed)
				(vias allowed)
				(pads allowed)
				(copperpour not_allowed)
				(footprints allowed)
			)
			(placement
				(enabled no)
				(sheetname "")
			)
			(fill
				(thermal_gap 0.5)
				(thermal_bridge_width 0.5)
				(island_removal_mode 0)
			)
			(polygon
				(pts
					(xy 148.235924 -239.183164) (xy 148.235924 -242.231164) (xy 146.203924 -242.231164) (xy 146.203924 -239.183164)
					(xy 148.134324 -239.183164) (xy 148.134324 -239.310164) (xy 146.280124 -239.310164) (xy 146.280124 -242.129564)
					(xy 148.159724 -242.129564) (xy 148.159724 -239.183164)
				)
			)
		)
	)
	(footprint ""
		(layer "F.Cu")
		(at 381.40386 -356.244906 90)
		(property "Reference" "C789"
			(at 0 0 90)
			(layer "F.SilkS")
			(hide yes)
			(effects
				(font
					(size 1.27 1.27)
				)
			)
		)
		(property "Value" ""
			(at 0 0 90)
			(layer "F.Fab")
			(effects
				(font
					(size 1.27 1.27)
				)
			)
		)
		(duplicate_pad_numbers_are_jumpers no)
		(fp_line
			(start 0.299974 -0.150114)
			(end 0.299974 0.150114)
			(stroke
				(width 0.1)
				(type default)
			)
			(layer "F.Fab")
		)
		(fp_line
			(start -0.299974 -0.150114)
			(end 0.299974 -0.150114)
			(stroke
				(width 0.1)
				(type default)
			)
			(layer "F.Fab")
		)
		(fp_line
			(start 0.299974 0.150114)
			(end -0.299974 0.150114)
			(stroke
				(width 0.1)
				(type default)
			)
			(layer "F.Fab")
		)
		(fp_line
			(start -0.299974 0.150114)
			(end -0.299974 -0.150114)
			(stroke
				(width 0.1)
				(type default)
			)
			(layer "F.Fab")
		)
		(pad "1" smd rect
			(at -0.2667 0 90)
			(size 0.3048 0.381)
			(layers "F.Cu" "F.Mask" "F.Paste")
			(net "P5E_PEX3_STN6_TX_DN<98>")
		)
		(pad "2" smd rect
			(at 0.2667 0 90)
			(size 0.3048 0.381)
			(layers "F.Cu" "F.Mask" "F.Paste")
			(net "P5E_PEX3_STN6_TX_C_DN<98>")
		)
	)
	(footprint ""
		(layer "F.Cu")
		(at 426.543724 -49.95291 180)
		(property "Reference" "R5907"
			(at 0 0 180)
			(layer "F.SilkS")
			(hide yes)
			(effects
				(font
					(size 1.27 1.27)
				)
			)
		)
		(property "Value" ""
			(at 0 0 180)
			(layer "F.Fab")
			(effects
				(font
					(size 1.27 1.27)
				)
			)
		)
		(duplicate_pad_numbers_are_jumpers no)
		(fp_line
			(start 0.7874 0.4064)
			(end -0.7874 0.4064)
			(stroke
				(width 0.1524)
				(type default)
			)
			(layer "F.SilkS")
		)
		(fp_line
			(start 0.7874 -0.4064)
			(end 0.7874 0.4064)
			(stroke
				(width 0.1524)
				(type default)
			)
			(layer "F.SilkS")
		)
		(fp_line
			(start -0.7874 0.4064)
			(end -0.7874 -0.4064)
			(stroke
				(width 0.1524)
				(type default)
			)
			(layer "F.SilkS")
		)
		(fp_line
			(start -0.7874 -0.4064)
			(end 0.7874 -0.4064)
			(stroke
				(width 0.1524)
				(type default)
			)
			(layer "F.SilkS")
		)
		(fp_line
			(start 0.67945 0.3048)
			(end 0.120396 0.3048)
			(stroke
				(width 0.1)
				(type default)
			)
			(layer "F.Fab")
		)
		(fp_line
			(start 0.67945 -0.3048)
			(end 0.67945 0.3048)
			(stroke
				(width 0.1)
				(type default)
			)
			(layer "F.Fab")
		)
		(fp_line
			(start 0.12065 -0.2794)
			(end 0.12065 -0.3048)
			(stroke
				(width 0.1)
				(type default)
			)
			(layer "F.Fab")
		)
		(fp_line
			(start 0.12065 -0.3048)
			(end 0.67945 -0.3048)
			(stroke
				(width 0.1)
				(type default)
			)
			(layer "F.Fab")
		)
		(fp_line
			(start 0.120396 0.3048)
			(end 0.120396 0.2794)
			(stroke
				(width 0.1)
				(type default)
			)
			(layer "F.Fab")
		)
		(fp_line
			(start 0.120396 0.2794)
			(end -0.12065 0.2794)
			(stroke
				(width 0.1)
				(type default)
			)
			(layer "F.Fab")
		)
		(fp_line
			(start -0.12065 0.3048)
			(end -0.67945 0.3048)
			(stroke
				(width 0.1)
				(type default)
			)
			(layer "F.Fab")
		)
		(fp_line
			(start -0.12065 0.2794)
			(end -0.12065 0.3048)
			(stroke
				(width 0.1)
				(type default)
			)
			(layer "F.Fab")
		)
		(fp_line
			(start -0.12065 -0.2794)
			(end 0.12065 -0.2794)
			(stroke
				(width 0.1)
				(type default)
			)
			(layer "F.Fab")
		)
		(fp_line
			(start -0.12065 -0.305054)
			(end -0.12065 -0.2794)
			(stroke
				(width 0.1)
				(type default)
			)
			(layer "F.Fab")
		)
		(fp_line
			(start -0.67945 0.3048)
			(end -0.67945 -0.305054)
			(stroke
				(width 0.1)
				(type default)
			)
			(layer "F.Fab")
		)
		(fp_line
			(start -0.67945 -0.305054)
			(end -0.12065 -0.305054)
			(stroke
				(width 0.1)
				(type default)
			)
			(layer "F.Fab")
		)
		(pad "1" smd circle
			(at -0.40005 0 180)
			(size 0 0)
			(layers "F.Cu" "F.Mask" "F.Paste")
			(net "SSD14_ADC_A0")
		)
		(pad "2" smd circle
			(at 0.40005 0 180)
			(size 0 0)
			(layers "F.Cu" "F.Mask" "F.Paste")
			(net "SMB_SSD14_ADC_SDA")
		)
	)
	(footprint ""
		(layer "F.Cu")
		(at 39.280592 -133.129782)
		(property "Reference" "C38"
			(at 0 0 0)
			(layer "F.SilkS")
			(hide yes)
			(effects
				(font
					(size 1.27 1.27)
				)
			)
		)
		(property "Value" ""
			(at 0 0 0)
			(layer "F.Fab")
			(effects
				(font
					(size 1.27 1.27)
				)
			)
		)
		(duplicate_pad_numbers_are_jumpers no)
		(fp_line
			(start -0.299974 -0.150114)
			(end 0.299974 -0.150114)
			(stroke
				(width 0.1)
				(type default)
			)
			(layer "F.Fab")
		)
		(fp_line
			(start -0.299974 0.150114)
			(end -0.299974 -0.150114)
			(stroke
				(width 0.1)
				(type default)
			)
			(layer "F.Fab")
		)
		(fp_line
			(start 0.299974 -0.150114)
			(end 0.299974 0.150114)
			(stroke
				(width 0.1)
				(type default)
			)
			(layer "F.Fab")
		)
		(fp_line
			(start 0.299974 0.150114)
			(end -0.299974 0.150114)
			(stroke
				(width 0.1)
				(type default)
			)
			(layer "F.Fab")
		)
		(pad "1" smd rect
			(at -0.2667 0)
			(size 0.3048 0.381)
			(layers "F.Cu" "F.Mask" "F.Paste")
			(net "P5E_PEX0_STN1_TX_DP<29>")
		)
		(pad "2" smd rect
			(at 0.2667 0)
			(size 0.3048 0.381)
			(layers "F.Cu" "F.Mask" "F.Paste")
			(net "P5E_PEX0_STN1_TX_C_DP<29>")
		)
	)
)
